#ISCELL
  mstr_misc dns *
  *
#ISCELL
  pure_quanta quanta_title_block_c *
  *
#ISCELL
  logical_power universal_gnd *
  page255_i1
#ISCELL
  logical_power universal_gnd *
  page255_i10
#CELL
  pure_quanta q_cap *
  page255_i11
#CELL
  pure_quanta isl99390frztr5935 *
  page255_i12
#CELL
  pure_quanta q_cap *
  page255_i13
#CELL
  pure_quanta q_res *
  page255_i14
#ISCELL
  logical_power vcc15 *
  page255_i15
#ISCELL
  logical_power universal_gnd *
  page255_i16
#CELL
  pure_quanta q_cap *
  page255_i17
#ISCELL
  standard offpage *
  page255_i18
#ISCELL
  standard offpage *
  page255_i19
#CELL
  pure_quanta q_res *
  page255_i2
#ISCELL
  logical_power universal_gnd *
  page255_i20
#ISCELL
  standard offpage *
  page255_i21
#ISCELL
  standard offpage *
  page255_i22
#ISCELL
  logical_power universal_gnd *
  page255_i23
#CELL
  pure_quanta q_cap *
  page255_i24
#CELL
  pure_quanta q_cap *
  page255_i25
#CELL
  pure_quanta q_res *
  page255_i26
#ISCELL
  logical_power vcc15 *
  page255_i27
#ISCELL
  logical_power universal_gnd *
  page255_i28
#CELL
  pure_quanta q_cap *
  page255_i29
#ISCELL
  logical_power universal_gnd *
  page255_i3
#ISCELL
  logical_power universal_gnd *
  page255_i30
#ISCELL
  standard offpage *
  page255_i31
#CELL
  pure_quanta q_inductor4p_14 *
  page255_i32
#CELL
  pure_quanta q_cap *
  page255_i33
#CELL
  pure_quanta q_cap *
  page255_i34
#CELL
  pure_quanta q_res *
  page255_i35
#ISCELL
  logical_power universal_gnd *
  page255_i36
#CELL
  pure_quanta q_cap *
  page255_i37
#CELL
  pure_quanta q_cap *
  page255_i38
#CELL
  pure_quanta q_cap *
  page255_i39
#CELL
  pure_quanta q_res *
  page255_i4
#CELL
  pure_quanta q_res *
  page255_i40
#ISCELL
  standard offpage *
  page255_i41
#CELL
  pure_quanta q_cap *
  page255_i42
#CELL
  pure_quanta q_cap *
  page255_i43
#ISCELL
  logical_power universal_gnd *
  page255_i44
#ISCELL
  logical_power vcc15 *
  page255_i45
#CELL
  pure_quanta q_res *
  page255_i46
#ISCELL
  standard offpage *
  page255_i47
#CELL
  pure_quanta q_cap *
  page255_i48
#CELL
  pure_quanta q_res *
  page255_i49
#ISCELL
  logical_power universal_gnd *
  page255_i5
#CELL
  pure_quanta q_inductor4p_14 *
  page255_i50
#CELL
  pure_quanta q_cap *
  page255_i51
#CELL
  pure_quanta q_cap *
  page255_i52
#CELL
  pure_quanta q_cap *
  page255_i53
#CELL
  pure_quanta q_cap *
  page255_i54
#ISCELL
  logical_power universal_gnd *
  page255_i55
#CELL
  pure_quanta q_cap *
  page255_i56
#ISCELL
  logical_power vcc15 *
  page255_i57
#ISCELL
  standard offpage *
  page255_i58
#CELL
  pure_quanta q_cap *
  page255_i59
#ISCELL
  standard offpage *
  page255_i6
#ISCELL
  logical_power universal_gnd *
  page255_i60
#ISCELL
  logical_power vcc15 *
  page255_i61
#ISCELL
  logical_power universal_gnd *
  page255_i62
#CELL
  pure_quanta q_cap *
  page255_i63
#CELL
  pure_quanta q_cap *
  page255_i64
#ISCELL
  logical_power vcc15 *
  page255_i65
#CELL
  pure_quanta isl99390frztr5935 *
  page255_i66
#ISCELL
  standard offpage *
  page255_i7
#ISCELL
  standard offpage *
  page255_i8
#ISCELL
  standard offpage *
  page255_i9
